# T6G (Grand Teton) — schematic netlist excerpt (pin names and nets, part order shuffled) for the footprints in the layout excerpt that follows; sources: Cadence DE-HDL packaged netlist, KiCad conversion of 04192023_DAF0TMB3IC0_F0TG_MB_C_brd_V02_OCP.brd

C2569  Q_CAP  22UF 4V 20% X6S  pkg C0402  page 70 : A = PVDDCR_SOC_P0 ; B = GND
R6719  Q_RES  1K 1% CHIP  pkg 0201LF  page 184 : A = P1V8_CPU1_RT_1D ; B = SMB_RT_CPU1_P0_R_SCL
C227  Q_CAP  4.7UF 6.3V 20% X6S  pkg 0402  page 323 : A = P0V9_CPU1_RT0_2A ; B = GND

(kicad_pcb
	(version 20260206)
	(generator "pcbnew")
	(generator_version "10.0")
	(general
		(thickness 1.6)
		(legacy_teardrops no)
	)
	(paper "A4")
	(title_block
		(title "04192023_DAF0TMB3IC0_F0TG_MB_C_brd_V02_OCP.brd")
		(comment 1 "Grand Teton / footprints 5582-5584 of 8354")
	)
	(layers
		(0 "F.Cu" signal "TOP")
		(4 "In1.Cu" signal "GND")
		(6 "In2.Cu" signal "IN1")
		(8 "In3.Cu" signal "GND1")
		(10 "In4.Cu" signal "IN2")
		(12 "In5.Cu" signal "GND2")
		(14 "In6.Cu" signal "IN3")
		(16 "In7.Cu" signal "GND3")
		(18 "In8.Cu" signal "VCC")
		(20 "In9.Cu" signal "VCC1")
		(22 "In10.Cu" signal "GND4")
		(24 "In11.Cu" signal "IN4")
		(26 "In12.Cu" signal "GND5")
		(28 "In13.Cu" signal "IN5")
		(30 "In14.Cu" signal "GND6")
		(32 "In15.Cu" signal "IN6")
		(34 "In16.Cu" signal "GND7")
		(2 "B.Cu" signal "BOTTOM")
		(9 "F.Adhes" user "F.Adhesive")
		(11 "B.Adhes" user "B.Adhesive")
		(13 "F.Paste" user "Package Geometry/Pastemask Top")
		(15 "B.Paste" user "Package Geometry/Pastemask Bottom")
		(5 "F.SilkS" user "Ref Des/Silkscreen Top")
		(7 "B.SilkS" user "Ref Des/Silkscreen Bottom")
		(1 "F.Mask" user "Board Geometry/Soldermask Top")
		(3 "B.Mask" user "Board Geometry/Soldermask Bottom")
		(17 "Dwgs.User" user "User.Drawings")
		(19 "Cmts.User" user "User.Comments")
		(21 "Eco1.User" user "User.Eco1")
		(23 "Eco2.User" user "User.Eco2")
		(25 "Edge.Cuts" user "Board Geometry/Outline")
		(27 "Margin" user)
		(31 "F.CrtYd" user "Package Geometry/Place Bound Top")
		(29 "B.CrtYd" user "Package Geometry/Place Bound Bottom")
		(35 "F.Fab" user "Ref Des/Assembly Top")
		(33 "B.Fab" user "Ref Des/Assembly Bottom")
	)
	(footprint ""
		(layer "B.Cu")
		(at 49.791366 -390.560052 90)
		(property "Reference" "C227"
			(at 0 0 90)
			(layer "B.SilkS")
			(hide yes)
			(effects
				(font
					(size 1.27 1.27)
				)
				(justify mirror)
			)
		)
		(property "Value" ""
			(at 0 0 90)
			(layer "B.Fab")
			(effects
				(font
					(size 1.27 1.27)
				)
				(justify mirror)
			)
		)
		(duplicate_pad_numbers_are_jumpers no)
		(fp_line
			(start 0.7874 -0.4064)
			(end -0.7874 -0.4064)
			(stroke
				(width 0.1524)
				(type default)
			)
			(layer "B.SilkS")
		)
		(fp_line
			(start -0.7874 -0.4064)
			(end -0.7874 0.4064)
			(stroke
				(width 0.1524)
				(type default)
			)
			(layer "B.SilkS")
		)
		(fp_line
			(start 0.7874 0.4064)
			(end 0.7874 -0.4064)
			(stroke
				(width 0.1524)
				(type default)
			)
			(layer "B.SilkS")
		)
		(fp_line
			(start -0.7874 0.4064)
			(end 0.7874 0.4064)
			(stroke
				(width 0.1524)
				(type default)
			)
			(layer "B.SilkS")
		)
		(fp_line
			(start 0.67945 -0.305054)
			(end 0.12065 -0.305054)
			(stroke
				(width 0.1)
				(type default)
			)
			(layer "B.Fab")
		)
		(fp_line
			(start 0.12065 -0.305054)
			(end 0.12065 -0.2794)
			(stroke
				(width 0.1)
				(type default)
			)
			(layer "B.Fab")
		)
		(fp_line
			(start -0.12065 -0.3048)
			(end -0.67945 -0.3048)
			(stroke
				(width 0.1)
				(type default)
			)
			(layer "B.Fab")
		)
		(fp_line
			(start -0.67945 -0.3048)
			(end -0.67945 0.3048)
			(stroke
				(width 0.1)
				(type default)
			)
			(layer "B.Fab")
		)
		(fp_line
			(start 0.12065 -0.2794)
			(end -0.12065 -0.2794)
			(stroke
				(width 0.1)
				(type default)
			)
			(layer "B.Fab")
		)
		(fp_line
			(start -0.12065 -0.2794)
			(end -0.12065 -0.3048)
			(stroke
				(width 0.1)
				(type default)
			)
			(layer "B.Fab")
		)
		(fp_line
			(start 0.12065 0.2794)
			(end 0.12065 0.3048)
			(stroke
				(width 0.1)
				(type default)
			)
			(layer "B.Fab")
		)
		(fp_line
			(start -0.120396 0.2794)
			(end 0.12065 0.2794)
			(stroke
				(width 0.1)
				(type default)
			)
			(layer "B.Fab")
		)
		(fp_line
			(start 0.67945 0.3048)
			(end 0.67945 -0.305054)
			(stroke
				(width 0.1)
				(type default)
			)
			(layer "B.Fab")
		)
		(fp_line
			(start 0.12065 0.3048)
			(end 0.67945 0.3048)
			(stroke
				(width 0.1)
				(type default)
			)
			(layer "B.Fab")
		)
		(fp_line
			(start -0.120396 0.3048)
			(end -0.120396 0.2794)
			(stroke
				(width 0.1)
				(type default)
			)
			(layer "B.Fab")
		)
		(fp_line
			(start -0.67945 0.3048)
			(end -0.120396 0.3048)
			(stroke
				(width 0.1)
				(type default)
			)
			(layer "B.Fab")
		)
		(pad "1" smd circle
			(at 0.40005 0 270)
			(size 0 0)
			(layers "B.Cu" "B.Mask" "B.Paste")
			(net "P0V9_CPU1_RT0_2A")
		)
		(pad "2" smd circle
			(at -0.40005 0 270)
			(size 0 0)
			(layers "B.Cu" "B.Mask" "B.Paste")
			(net "GND")
		)
	)
	(footprint ""
		(layer "B.Cu")
		(at 216.027 -335.153 90)
		(property "Reference" "R6719"
			(at 0 0 90)
			(layer "B.SilkS")
			(hide yes)
			(effects
				(font
					(size 1.27 1.27)
				)
				(justify mirror)
			)
		)
		(property "Value" ""
			(at 0 0 90)
			(layer "B.Fab")
			(effects
				(font
					(size 1.27 1.27)
				)
				(justify mirror)
			)
		)
		(duplicate_pad_numbers_are_jumpers no)
		(fp_line
			(start 0.32512 -0.175006)
			(end -0.32512 -0.175006)
			(stroke
				(width 0.1)
				(type default)
			)
			(layer "B.Fab")
		)
		(fp_line
			(start -0.32512 -0.175006)
			(end -0.32512 0.175006)
			(stroke
				(width 0.1)
				(type default)
			)
			(layer "B.Fab")
		)
		(fp_line
			(start 0.32512 0.175006)
			(end 0.32512 -0.175006)
			(stroke
				(width 0.1)
				(type default)
			)
			(layer "B.Fab")
		)
		(fp_line
			(start -0.32512 0.175006)
			(end 0.32512 0.175006)
			(stroke
				(width 0.1)
				(type default)
			)
			(layer "B.Fab")
		)
		(pad "1" smd rect
			(at 0.2667 0 270)
			(size 0.3048 0.381)
			(layers "B.Cu" "B.Mask" "B.Paste")
			(net "P1V8_CPU1_RT_1D")
		)
		(pad "2" smd rect
			(at -0.2667 0 90)
			(size 0.3048 0.381)
			(layers "B.Cu" "B.Mask" "B.Paste")
			(net "SMB_RT_CPU1_P0_R_SCL")
		)
	)
	(footprint ""
		(layer "B.Cu")
		(at 354.152454 -253.43231)
		(property "Reference" "C2569"
			(at 0 0 0)
			(layer "B.SilkS")
			(hide yes)
			(effects
				(font
					(size 1.27 1.27)
				)
				(justify mirror)
			)
		)
		(property "Value" ""
			(at 0 0 0)
			(layer "B.Fab")
			(effects
				(font
					(size 1.27 1.27)
				)
				(justify mirror)
			)
		)
		(duplicate_pad_numbers_are_jumpers no)
		(fp_line
			(start -0.7874 -0.4064)
			(end -0.7874 0.4064)
			(stroke
				(width 0.1524)
				(type default)
			)
			(layer "B.SilkS")
		)
		(fp_line
			(start -0.7874 0.4064)
			(end 0.7874 0.4064)
			(stroke
				(width 0.1524)
				(type default)
			)
			(layer "B.SilkS")
		)
		(fp_line
			(start 0.7874 -0.4064)
			(end -0.7874 -0.4064)
			(stroke
				(width 0.1524)
				(type default)
			)
			(layer "B.SilkS")
		)
		(fp_line
			(start 0.7874 0.4064)
			(end 0.7874 -0.4064)
			(stroke
				(width 0.1524)
				(type default)
			)
			(layer "B.SilkS")
		)
		(fp_line
			(start -0.67945 -0.3048)
			(end -0.67945 0.3048)
			(stroke
				(width 0.1)
				(type default)
			)
			(layer "B.Fab")
		)
		(fp_line
			(start -0.67945 0.3048)
			(end -0.120396 0.3048)
			(stroke
				(width 0.1)
				(type default)
			)
			(layer "B.Fab")
		)
		(fp_line
			(start -0.12065 -0.3048)
			(end -0.67945 -0.3048)
			(stroke
				(width 0.1)
				(type default)
			)
			(layer "B.Fab")
		)
		(fp_line
			(start -0.12065 -0.2794)
			(end -0.12065 -0.3048)
			(stroke
				(width 0.1)
				(type default)
			)
			(layer "B.Fab")
		)
		(fp_line
			(start -0.120396 0.2794)
			(end 0.12065 0.2794)
			(stroke
				(width 0.1)
				(type default)
			)
			(layer "B.Fab")
		)
		(fp_line
			(start -0.120396 0.3048)
			(end -0.120396 0.2794)
			(stroke
				(width 0.1)
				(type default)
			)
			(layer "B.Fab")
		)
		(fp_line
			(start 0.12065 -0.305054)
			(end 0.12065 -0.2794)
			(stroke
				(width 0.1)
				(type default)
			)
			(layer "B.Fab")
		)
		(fp_line
			(start 0.12065 -0.2794)
			(end -0.12065 -0.2794)
			(stroke
				(width 0.1)
				(type default)
			)
			(layer "B.Fab")
		)
		(fp_line
			(start 0.12065 0.2794)
			(end 0.12065 0.3048)
			(stroke
				(width 0.1)
				(type default)
			)
			(layer "B.Fab")
		)
		(fp_line
			(start 0.12065 0.3048)
			(end 0.67945 0.3048)
			(stroke
				(width 0.1)
				(type default)
			)
			(layer "B.Fab")
		)
		(fp_line
			(start 0.67945 -0.305054)
			(end 0.12065 -0.305054)
			(stroke
				(width 0.1)
				(type default)
			)
			(layer "B.Fab")
		)
		(fp_line
			(start 0.67945 0.3048)
			(end 0.67945 -0.305054)
			(stroke
				(width 0.1)
				(type default)
			)
			(layer "B.Fab")
		)
		(pad "1" smd circle
			(at 0.40005 0 180)
			(size 0 0)
			(layers "B.Cu" "B.Mask" "B.Paste")
			(net "PVDDCR_SOC_P0")
		)
		(pad "2" smd circle
			(at -0.40005 0 180)
			(size 0 0)
			(layers "B.Cu" "B.Mask" "B.Paste")
			(net "GND")
		)
	)
)
